# T6G (Grand Teton) — schematic netlist excerpt (pin names and nets, part order shuffled) for the footprints in the layout excerpt that follows; sources: Cadence DE-HDL packaged netlist, KiCad conversion of 04192023_DAF0TMB3IC0_F0TG_MB_C_brd_V02_OCP.brd

C423  Q_CAP  1UF 4V 20% X6S  pkg 0201  page 345 : A = P0V9_CPU1_RT_2D ; B = GND
C2603  Q_CAP  22UF 4V 20% X6S  pkg C0402  page 70 : A = PVDD11_S3_P0 ; B = GND
PR429  Q_RES  0 5% CHIP  pkg 0402LF  page 220 : A = PVDDCR_CPU1_P1_VOS6 ; B = PVDDCR_CPU1_P1

(kicad_pcb
	(version 20260206)
	(generator "pcbnew")
	(generator_version "10.0")
	(general
		(thickness 1.6)
		(legacy_teardrops no)
	)
	(paper "A4")
	(title_block
		(title "04192023_DAF0TMB3IC0_F0TG_MB_C_brd_V02_OCP.brd")
		(comment 1 "Grand Teton / footprints 6803-6805 of 8354")
	)
	(layers
		(0 "F.Cu" signal "TOP")
		(4 "In1.Cu" signal "GND")
		(6 "In2.Cu" signal "IN1")
		(8 "In3.Cu" signal "GND1")
		(10 "In4.Cu" signal "IN2")
		(12 "In5.Cu" signal "GND2")
		(14 "In6.Cu" signal "IN3")
		(16 "In7.Cu" signal "GND3")
		(18 "In8.Cu" signal "VCC")
		(20 "In9.Cu" signal "VCC1")
		(22 "In10.Cu" signal "GND4")
		(24 "In11.Cu" signal "IN4")
		(26 "In12.Cu" signal "GND5")
		(28 "In13.Cu" signal "IN5")
		(30 "In14.Cu" signal "GND6")
		(32 "In15.Cu" signal "IN6")
		(34 "In16.Cu" signal "GND7")
		(2 "B.Cu" signal "BOTTOM")
		(9 "F.Adhes" user "F.Adhesive")
		(11 "B.Adhes" user "B.Adhesive")
		(13 "F.Paste" user "Package Geometry/Pastemask Top")
		(15 "B.Paste" user "Package Geometry/Pastemask Bottom")
		(5 "F.SilkS" user "Ref Des/Silkscreen Top")
		(7 "B.SilkS" user "Ref Des/Silkscreen Bottom")
		(1 "F.Mask" user "Board Geometry/Soldermask Top")
		(3 "B.Mask" user "Board Geometry/Soldermask Bottom")
		(17 "Dwgs.User" user "User.Drawings")
		(19 "Cmts.User" user "User.Comments")
		(21 "Eco1.User" user "User.Eco1")
		(23 "Eco2.User" user "User.Eco2")
		(25 "Edge.Cuts" user "Board Geometry/Outline")
		(27 "Margin" user)
		(31 "F.CrtYd" user "Package Geometry/Place Bound Top")
		(29 "B.CrtYd" user "Package Geometry/Place Bound Bottom")
		(35 "F.Fab" user "Ref Des/Assembly Top")
		(33 "B.Fab" user "Ref Des/Assembly Bottom")
	)
	(footprint ""
		(layer "B.Cu")
		(at 159.018986 -390.909302 90)
		(property "Reference" "C423"
			(at 0 0 90)
			(layer "B.SilkS")
			(hide yes)
			(effects
				(font
					(size 1.27 1.27)
				)
				(justify mirror)
			)
		)
		(property "Value" ""
			(at 0 0 90)
			(layer "B.Fab")
			(effects
				(font
					(size 1.27 1.27)
				)
				(justify mirror)
			)
		)
		(duplicate_pad_numbers_are_jumpers no)
		(fp_line
			(start 0.299974 -0.150114)
			(end -0.299974 -0.150114)
			(stroke
				(width 0.1)
				(type default)
			)
			(layer "B.Fab")
		)
		(fp_line
			(start -0.299974 -0.150114)
			(end -0.299974 0.150114)
			(stroke
				(width 0.1)
				(type default)
			)
			(layer "B.Fab")
		)
		(fp_line
			(start 0.299974 0.150114)
			(end 0.299974 -0.150114)
			(stroke
				(width 0.1)
				(type default)
			)
			(layer "B.Fab")
		)
		(fp_line
			(start -0.299974 0.150114)
			(end 0.299974 0.150114)
			(stroke
				(width 0.1)
				(type default)
			)
			(layer "B.Fab")
		)
		(pad "1" smd rect
			(at 0.2667 0 270)
			(size 0.3048 0.381)
			(layers "B.Cu" "B.Mask" "B.Paste")
			(net "P0V9_CPU1_RT_2D")
		)
		(pad "2" smd rect
			(at -0.2667 0 270)
			(size 0.3048 0.381)
			(layers "B.Cu" "B.Mask" "B.Paste")
			(net "GND")
		)
	)
	(footprint ""
		(layer "B.Cu")
		(at 348.818454 -266.00531)
		(property "Reference" "C2603"
			(at 0 0 0)
			(layer "B.SilkS")
			(hide yes)
			(effects
				(font
					(size 1.27 1.27)
				)
				(justify mirror)
			)
		)
		(property "Value" ""
			(at 0 0 0)
			(layer "B.Fab")
			(effects
				(font
					(size 1.27 1.27)
				)
				(justify mirror)
			)
		)
		(duplicate_pad_numbers_are_jumpers no)
		(fp_line
			(start -0.7874 -0.4064)
			(end -0.7874 0.4064)
			(stroke
				(width 0.1524)
				(type default)
			)
			(layer "B.SilkS")
		)
		(fp_line
			(start -0.7874 0.4064)
			(end 0.7874 0.4064)
			(stroke
				(width 0.1524)
				(type default)
			)
			(layer "B.SilkS")
		)
		(fp_line
			(start 0.7874 -0.4064)
			(end -0.7874 -0.4064)
			(stroke
				(width 0.1524)
				(type default)
			)
			(layer "B.SilkS")
		)
		(fp_line
			(start 0.7874 0.4064)
			(end 0.7874 -0.4064)
			(stroke
				(width 0.1524)
				(type default)
			)
			(layer "B.SilkS")
		)
		(fp_line
			(start -0.67945 -0.3048)
			(end -0.67945 0.3048)
			(stroke
				(width 0.1)
				(type default)
			)
			(layer "B.Fab")
		)
		(fp_line
			(start -0.67945 0.3048)
			(end -0.120396 0.3048)
			(stroke
				(width 0.1)
				(type default)
			)
			(layer "B.Fab")
		)
		(fp_line
			(start -0.12065 -0.3048)
			(end -0.67945 -0.3048)
			(stroke
				(width 0.1)
				(type default)
			)
			(layer "B.Fab")
		)
		(fp_line
			(start -0.12065 -0.2794)
			(end -0.12065 -0.3048)
			(stroke
				(width 0.1)
				(type default)
			)
			(layer "B.Fab")
		)
		(fp_line
			(start -0.120396 0.2794)
			(end 0.12065 0.2794)
			(stroke
				(width 0.1)
				(type default)
			)
			(layer "B.Fab")
		)
		(fp_line
			(start -0.120396 0.3048)
			(end -0.120396 0.2794)
			(stroke
				(width 0.1)
				(type default)
			)
			(layer "B.Fab")
		)
		(fp_line
			(start 0.12065 -0.305054)
			(end 0.12065 -0.2794)
			(stroke
				(width 0.1)
				(type default)
			)
			(layer "B.Fab")
		)
		(fp_line
			(start 0.12065 -0.2794)
			(end -0.12065 -0.2794)
			(stroke
				(width 0.1)
				(type default)
			)
			(layer "B.Fab")
		)
		(fp_line
			(start 0.12065 0.2794)
			(end 0.12065 0.3048)
			(stroke
				(width 0.1)
				(type default)
			)
			(layer "B.Fab")
		)
		(fp_line
			(start 0.12065 0.3048)
			(end 0.67945 0.3048)
			(stroke
				(width 0.1)
				(type default)
			)
			(layer "B.Fab")
		)
		(fp_line
			(start 0.67945 -0.305054)
			(end 0.12065 -0.305054)
			(stroke
				(width 0.1)
				(type default)
			)
			(layer "B.Fab")
		)
		(fp_line
			(start 0.67945 0.3048)
			(end 0.67945 -0.305054)
			(stroke
				(width 0.1)
				(type default)
			)
			(layer "B.Fab")
		)
		(pad "1" smd circle
			(at 0.40005 0 180)
			(size 0 0)
			(layers "B.Cu" "B.Mask" "B.Paste")
			(net "PVDD11_S3_P0")
		)
		(pad "2" smd circle
			(at -0.40005 0 180)
			(size 0 0)
			(layers "B.Cu" "B.Mask" "B.Paste")
			(net "GND")
		)
	)
	(footprint ""
		(layer "B.Cu")
		(at 100.067872 -342.604598 -90)
		(property "Reference" "PR429"
			(at 0 0 90)
			(layer "B.SilkS")
			(hide yes)
			(effects
				(font
					(size 1.27 1.27)
				)
				(justify mirror)
			)
		)
		(property "Value" ""
			(at 0 0 90)
			(layer "B.Fab")
			(effects
				(font
					(size 1.27 1.27)
				)
				(justify mirror)
			)
		)
		(duplicate_pad_numbers_are_jumpers no)
		(fp_line
			(start -0.7874 0.4064)
			(end 0.7874 0.4064)
			(stroke
				(width 0.1524)
				(type default)
			)
			(layer "B.SilkS")
		)
		(fp_line
			(start 0.7874 0.4064)
			(end 0.7874 -0.4064)
			(stroke
				(width 0.1524)
				(type default)
			)
			(layer "B.SilkS")
		)
		(fp_line
			(start -0.7874 -0.4064)
			(end -0.7874 0.4064)
			(stroke
				(width 0.1524)
				(type default)
			)
			(layer "B.SilkS")
		)
		(fp_line
			(start 0.7874 -0.4064)
			(end -0.7874 -0.4064)
			(stroke
				(width 0.1524)
				(type default)
			)
			(layer "B.SilkS")
		)
		(fp_line
			(start -0.67945 0.3048)
			(end -0.120396 0.3048)
			(stroke
				(width 0.1)
				(type default)
			)
			(layer "B.Fab")
		)
		(fp_line
			(start -0.120396 0.3048)
			(end -0.120396 0.2794)
			(stroke
				(width 0.1)
				(type default)
			)
			(layer "B.Fab")
		)
		(fp_line
			(start 0.12065 0.3048)
			(end 0.67945 0.3048)
			(stroke
				(width 0.1)
				(type default)
			)
			(layer "B.Fab")
		)
		(fp_line
			(start 0.67945 0.3048)
			(end 0.67945 -0.305054)
			(stroke
				(width 0.1)
				(type default)
			)
			(layer "B.Fab")
		)
		(fp_line
			(start -0.120396 0.2794)
			(end 0.12065 0.2794)
			(stroke
				(width 0.1)
				(type default)
			)
			(layer "B.Fab")
		)
		(fp_line
			(start 0.12065 0.2794)
			(end 0.12065 0.3048)
			(stroke
				(width 0.1)
				(type default)
			)
			(layer "B.Fab")
		)
		(fp_line
			(start -0.12065 -0.2794)
			(end -0.12065 -0.3048)
			(stroke
				(width 0.1)
				(type default)
			)
			(layer "B.Fab")
		)
		(fp_line
			(start 0.12065 -0.2794)
			(end -0.12065 -0.2794)
			(stroke
				(width 0.1)
				(type default)
			)
			(layer "B.Fab")
		)
		(fp_line
			(start -0.67945 -0.3048)
			(end -0.67945 0.3048)
			(stroke
				(width 0.1)
				(type default)
			)
			(layer "B.Fab")
		)
		(fp_line
			(start -0.12065 -0.3048)
			(end -0.67945 -0.3048)
			(stroke
				(width 0.1)
				(type default)
			)
			(layer "B.Fab")
		)
		(fp_line
			(start 0.12065 -0.305054)
			(end 0.12065 -0.2794)
			(stroke
				(width 0.1)
				(type default)
			)
			(layer "B.Fab")
		)
		(fp_line
			(start 0.67945 -0.305054)
			(end 0.12065 -0.305054)
			(stroke
				(width 0.1)
				(type default)
			)
			(layer "B.Fab")
		)
		(pad "1" smd circle
			(at 0.40005 0 90)
			(size 0 0)
			(layers "B.Cu" "B.Mask" "B.Paste")
			(net "PVDDCR_CPU1_P1_VOS6")
		)
		(pad "2" smd circle
			(at -0.40005 0 90)
			(size 0 0)
			(layers "B.Cu" "B.Mask" "B.Paste")
			(net "PVDDCR_CPU1_P1")
		)
	)
)
